(kicad_pcb
	(version 20260206)
	(generator "pcbnew")
	(generator_version "10.0")
	(general
		(thickness 1.6)
		(legacy_teardrops no)
	)
	(paper "A4")
	(title_block
		(title "04192023_DAF0TMB3IC0_F0TG_MB_C_brd_V02_OCP.brd")
		(comment 1 "Grand Teton / footprints 546-551 of 8354")
	)
	(layers
		(0 "F.Cu" signal "TOP")
		(4 "In1.Cu" signal "GND")
		(6 "In2.Cu" signal "IN1")
		(8 "In3.Cu" signal "GND1")
		(10 "In4.Cu" signal "IN2")
		(12 "In5.Cu" signal "GND2")
		(14 "In6.Cu" signal "IN3")
		(16 "In7.Cu" signal "GND3")
		(18 "In8.Cu" signal "VCC")
		(20 "In9.Cu" signal "VCC1")
		(22 "In10.Cu" signal "GND4")
		(24 "In11.Cu" signal "IN4")
		(26 "In12.Cu" signal "GND5")
		(28 "In13.Cu" signal "IN5")
		(30 "In14.Cu" signal "GND6")
		(32 "In15.Cu" signal "IN6")
		(34 "In16.Cu" signal "GND7")
		(2 "B.Cu" signal "BOTTOM")
		(9 "F.Adhes" user "F.Adhesive")
		(11 "B.Adhes" user "B.Adhesive")
		(13 "F.Paste" user "Package Geometry/Pastemask Top")
		(15 "B.Paste" user "Package Geometry/Pastemask Bottom")
		(5 "F.SilkS" user "Ref Des/Silkscreen Top")
		(7 "B.SilkS" user "Ref Des/Silkscreen Bottom")
		(1 "F.Mask" user "Board Geometry/Soldermask Top")
		(3 "B.Mask" user "Board Geometry/Soldermask Bottom")
		(17 "Dwgs.User" user "User.Drawings")
		(19 "Cmts.User" user "User.Comments")
		(21 "Eco1.User" user "User.Eco1")
		(23 "Eco2.User" user "User.Eco2")
		(25 "Edge.Cuts" user "Board Geometry/Outline")
		(27 "Margin" user)
		(31 "F.CrtYd" user "Package Geometry/Place Bound Top")
		(29 "B.CrtYd" user "Package Geometry/Place Bound Bottom")
		(35 "F.Fab" user "Ref Des/Assembly Top")
		(33 "B.Fab" user "Ref Des/Assembly Bottom")
	)
	(footprint ""
		(layer "F.Cu")
		(at 366.288574 -5.077206 180)
		(property "Reference" "J63"
			(at -4.50723 -1.072642 90)
			(unlocked yes)
			(layer "F.SilkS")
			(effects
				(font
					(size 0.7874 0.5842)
					(thickness 0.1524)
				)
				(justify left)
			)
		)
		(property "Value" ""
			(at 0 0 180)
			(layer "F.Fab")
			(effects
				(font
					(size 1.27 1.27)
				)
			)
		)
		(duplicate_pad_numbers_are_jumpers no)
		(fp_line
			(start 1.2192 2.06756)
			(end -1.2192 2.06756)
			(stroke
				(width 0.1524)
				(type default)
			)
			(layer "F.SilkS")
		)
		(fp_line
			(start 1.2192 -2.06756)
			(end 1.2192 2.06756)
			(stroke
				(width 0.1524)
				(type default)
			)
			(layer "F.SilkS")
		)
		(fp_line
			(start -1.2192 2.06756)
			(end -1.2192 -2.06756)
			(stroke
				(width 0.1524)
				(type default)
			)
			(layer "F.SilkS")
		)
		(fp_line
			(start -1.2192 -2.06756)
			(end 1.2192 -2.06756)
			(stroke
				(width 0.1524)
				(type default)
			)
			(layer "F.SilkS")
		)
		(pad "" np_thru_hole circle
			(at -2.8829 -1.27 90)
			(size 1.0414 1.0414)
			(drill 1.0414)
			(layers "*.Cu" "*.Mask")
			(clearance 0.381)
			(thermal_gap 0.381)
		)
		(pad "" np_thru_hole circle
			(at -2.8829 1.27 90)
			(size 1.0414 1.0414)
			(drill 1.0414)
			(layers "*.Cu" "*.Mask")
			(clearance 0.381)
			(thermal_gap 0.381)
		)
		(pad "" np_thru_hole circle
			(at 3.4671 -1.27 90)
			(size 1.0414 1.0414)
			(drill 1.0414)
			(layers "*.Cu" "*.Mask")
			(clearance 0.381)
			(thermal_gap 0.381)
		)
		(pad "" np_thru_hole circle
			(at 3.4671 1.27 90)
			(size 1.0414 1.0414)
			(drill 1.0414)
			(layers "*.Cu" "*.Mask")
			(clearance 0.381)
			(thermal_gap 0.381)
		)
		(pad "1" smd rect
			(at 0.8255 -0.249936 90)
			(size 0.3048 0.508)
			(layers "F.Cu" "F.Mask" "F.Paste")
			(net "DELTA_L_85_5INCH_TOP_DP")
		)
		(pad "2" smd rect
			(at 0.8255 0.249936 90)
			(size 0.3048 0.508)
			(layers "F.Cu" "F.Mask" "F.Paste")
			(net "DELTA_L_85_5INCH_TOP_DN")
		)
		(pad "3" smd circle
			(at 0 0 180)
			(size 0 0)
			(layers "F.Cu" "F.Mask" "F.Paste")
			(net "DELTA_L_GND_1")
		)
		(zone
			(layer "F.Cu")
			(hatch none 0.5)
			(connect_pads
				(clearance 0)
			)
			(min_thickness 0.25)
			(keepout
				(tracks not_allowed)
				(vias allowed)
				(pads allowed)
				(copperpour not_allowed)
				(footprints allowed)
			)
			(placement
				(enabled no)
				(sheetname "")
			)
			(fill
				(thermal_gap 0.5)
				(thermal_bridge_width 0.5)
				(island_removal_mode 0)
			)
			(polygon
				(pts
					(xy 365.170974 -4.528566) (xy 365.170974 -4.62407) (xy 365.767874 -4.62407) (xy 365.767874 -5.03047)
					(xy 365.170974 -5.03047) (xy 365.170974 -5.123942) (xy 365.767874 -5.123942) (xy 365.767874 -5.530342)
					(xy 365.170974 -5.530342) (xy 365.170974 -5.625846) (xy 365.869474 -5.625846) (xy 365.869474 -4.528566)
				)
			)
		)
		(zone
			(layers "F.Cu" "B.Cu" "In1.Cu" "In2.Cu" "In3.Cu" "In4.Cu" "In5.Cu" "In6.Cu"
				"In7.Cu" "In8.Cu" "In9.Cu" "In10.Cu" "In11.Cu" "In12.Cu" "In13.Cu" "In14.Cu"
				"In15.Cu" "In16.Cu"
			)
			(hatch none 0.5)
			(connect_pads
				(clearance 0)
			)
			(min_thickness 0.25)
			(keepout
				(tracks not_allowed)
				(vias allowed)
				(pads allowed)
				(copperpour not_allowed)
				(footprints allowed)
			)
			(placement
				(enabled no)
				(sheetname "")
			)
			(fill
				(thermal_gap 0.5)
				(thermal_bridge_width 0.5)
				(island_removal_mode 0)
			)
			(polygon
				(pts
					(arc
						(start 363.748574 -6.347206)
						(mid 361.894374 -6.347206)
						(end 363.748574 -6.347206)
					)
				)
			)
		)
		(zone
			(layers "F.Cu" "B.Cu" "In1.Cu" "In2.Cu" "In3.Cu" "In4.Cu" "In5.Cu" "In6.Cu"
				"In7.Cu" "In8.Cu" "In9.Cu" "In10.Cu" "In11.Cu" "In12.Cu" "In13.Cu" "In14.Cu"
				"In15.Cu" "In16.Cu"
			)
			(hatch none 0.5)
			(connect_pads
				(clearance 0)
			)
			(min_thickness 0.25)
			(keepout
				(tracks not_allowed)
				(vias allowed)
				(pads allowed)
				(copperpour not_allowed)
				(footprints allowed)
			)
			(placement
				(enabled no)
				(sheetname "")
			)
			(fill
				(thermal_gap 0.5)
				(thermal_bridge_width 0.5)
				(island_removal_mode 0)
			)
			(polygon
				(pts
					(arc
						(start 363.748574 -3.807206)
						(mid 361.894374 -3.807206)
						(end 363.748574 -3.807206)
					)
				)
			)
		)
		(zone
			(layers "F.Cu" "B.Cu" "In1.Cu" "In2.Cu" "In3.Cu" "In4.Cu" "In5.Cu" "In6.Cu"
				"In7.Cu" "In8.Cu" "In9.Cu" "In10.Cu" "In11.Cu" "In12.Cu" "In13.Cu" "In14.Cu"
				"In15.Cu" "In16.Cu"
			)
			(hatch none 0.5)
			(connect_pads
				(clearance 0)
			)
			(min_thickness 0.25)
			(keepout
				(tracks not_allowed)
				(vias allowed)
				(pads allowed)
				(copperpour not_allowed)
				(footprints allowed)
			)
			(placement
				(enabled no)
				(sheetname "")
			)
			(fill
				(thermal_gap 0.5)
				(thermal_bridge_width 0.5)
				(island_removal_mode 0)
			)
			(polygon
				(pts
					(arc
						(start 370.098574 -6.347206)
						(mid 368.244374 -6.347206)
						(end 370.098574 -6.347206)
					)
				)
			)
		)
		(zone
			(layers "F.Cu" "B.Cu" "In1.Cu" "In2.Cu" "In3.Cu" "In4.Cu" "In5.Cu" "In6.Cu"
				"In7.Cu" "In8.Cu" "In9.Cu" "In10.Cu" "In11.Cu" "In12.Cu" "In13.Cu" "In14.Cu"
				"In15.Cu" "In16.Cu"
			)
			(hatch none 0.5)
			(connect_pads
				(clearance 0)
			)
			(min_thickness 0.25)
			(keepout
				(tracks not_allowed)
				(vias allowed)
				(pads allowed)
				(copperpour not_allowed)
				(footprints allowed)
			)
			(placement
				(enabled no)
				(sheetname "")
			)
			(fill
				(thermal_gap 0.5)
				(thermal_bridge_width 0.5)
				(island_removal_mode 0)
			)
			(polygon
				(pts
					(arc
						(start 370.098574 -3.807206)
						(mid 368.244374 -3.807206)
						(end 370.098574 -3.807206)
					)
				)
			)
		)
	)
	(footprint ""
		(layer "F.Cu")
		(at 100.696268 -395.6304 -90)
		(property "Reference" "R731"
			(at 0 0 270)
			(layer "F.SilkS")
			(hide yes)
			(effects
				(font
					(size 1.27 1.27)
				)
			)
		)
		(property "Value" ""
			(at 0 0 270)
			(layer "F.Fab")
			(effects
				(font
					(size 1.27 1.27)
				)
			)
		)
		(duplicate_pad_numbers_are_jumpers no)
		(fp_line
			(start -0.32512 0.175006)
			(end -0.32512 -0.175006)
			(stroke
				(width 0.1)
				(type default)
			)
			(layer "F.Fab")
		)
		(fp_line
			(start 0.32512 0.175006)
			(end -0.32512 0.175006)
			(stroke
				(width 0.1)
				(type default)
			)
			(layer "F.Fab")
		)
		(fp_line
			(start -0.32512 -0.175006)
			(end 0.32512 -0.175006)
			(stroke
				(width 0.1)
				(type default)
			)
			(layer "F.Fab")
		)
		(fp_line
			(start 0.32512 -0.175006)
			(end 0.32512 0.175006)
			(stroke
				(width 0.1)
				(type default)
			)
			(layer "F.Fab")
		)
		(pad "1" smd rect
			(at -0.2667 0 270)
			(size 0.3048 0.381)
			(layers "F.Cu" "F.Mask" "F.Paste")
			(net "RST_RT_CPU1_P1_PERST_N")
		)
		(pad "2" smd rect
			(at 0.2667 0 90)
			(size 0.3048 0.381)
			(layers "F.Cu" "F.Mask" "F.Paste")
			(net "RST_RT_CPU1_P1_PERST_R_N")
		)
	)
	(footprint ""
		(layer "F.Cu")
		(at 308.420516 -435.720744 -90)
		(property "Reference" "R3437"
			(at 0 0 270)
			(layer "F.SilkS")
			(hide yes)
			(effects
				(font
					(size 1.27 1.27)
				)
			)
		)
		(property "Value" ""
			(at 0 0 270)
			(layer "F.Fab")
			(effects
				(font
					(size 1.27 1.27)
				)
			)
		)
		(duplicate_pad_numbers_are_jumpers no)
		(fp_line
			(start -0.7874 0.4064)
			(end -0.7874 -0.4064)
			(stroke
				(width 0.1524)
				(type default)
			)
			(layer "F.SilkS")
		)
		(fp_line
			(start 0.7874 0.4064)
			(end -0.7874 0.4064)
			(stroke
				(width 0.1524)
				(type default)
			)
			(layer "F.SilkS")
		)
		(fp_line
			(start -0.7874 -0.4064)
			(end 0.7874 -0.4064)
			(stroke
				(width 0.1524)
				(type default)
			)
			(layer "F.SilkS")
		)
		(fp_line
			(start 0.7874 -0.4064)
			(end 0.7874 0.4064)
			(stroke
				(width 0.1524)
				(type default)
			)
			(layer "F.SilkS")
		)
		(fp_line
			(start -0.67945 0.3048)
			(end -0.67945 -0.305054)
			(stroke
				(width 0.1)
				(type default)
			)
			(layer "F.Fab")
		)
		(fp_line
			(start -0.12065 0.3048)
			(end -0.67945 0.3048)
			(stroke
				(width 0.1)
				(type default)
			)
			(layer "F.Fab")
		)
		(fp_line
			(start 0.120396 0.3048)
			(end 0.120396 0.2794)
			(stroke
				(width 0.1)
				(type default)
			)
			(layer "F.Fab")
		)
		(fp_line
			(start 0.67945 0.3048)
			(end 0.120396 0.3048)
			(stroke
				(width 0.1)
				(type default)
			)
			(layer "F.Fab")
		)
		(fp_line
			(start -0.12065 0.2794)
			(end -0.12065 0.3048)
			(stroke
				(width 0.1)
				(type default)
			)
			(layer "F.Fab")
		)
		(fp_line
			(start 0.120396 0.2794)
			(end -0.12065 0.2794)
			(stroke
				(width 0.1)
				(type default)
			)
			(layer "F.Fab")
		)
		(fp_line
			(start -0.12065 -0.2794)
			(end 0.12065 -0.2794)
			(stroke
				(width 0.1)
				(type default)
			)
			(layer "F.Fab")
		)
		(fp_line
			(start 0.12065 -0.2794)
			(end 0.12065 -0.3048)
			(stroke
				(width 0.1)
				(type default)
			)
			(layer "F.Fab")
		)
		(fp_line
			(start 0.12065 -0.3048)
			(end 0.67945 -0.3048)
			(stroke
				(width 0.1)
				(type default)
			)
			(layer "F.Fab")
		)
		(fp_line
			(start 0.67945 -0.3048)
			(end 0.67945 0.3048)
			(stroke
				(width 0.1)
				(type default)
			)
			(layer "F.Fab")
		)
		(fp_line
			(start -0.67945 -0.305054)
			(end -0.12065 -0.305054)
			(stroke
				(width 0.1)
				(type default)
			)
			(layer "F.Fab")
		)
		(fp_line
			(start -0.12065 -0.305054)
			(end -0.12065 -0.2794)
			(stroke
				(width 0.1)
				(type default)
			)
			(layer "F.Fab")
		)
		(pad "1" smd circle
			(at -0.40005 0 270)
			(size 0 0)
			(layers "F.Cu" "F.Mask" "F.Paste")
			(net "P3V3_AUX")
		)
		(pad "2" smd circle
			(at 0.40005 0 270)
			(size 0 0)
			(layers "F.Cu" "F.Mask" "F.Paste")
			(net "GPU_FPGA_OVERT_ISO_N")
		)
	)
	(footprint ""
		(layer "F.Cu")
		(at 319.999106 -416.899344 -90)
		(property "Reference" "C6511"
			(at 0 0 270)
			(layer "F.SilkS")
			(hide yes)
			(effects
				(font
					(size 1.27 1.27)
				)
			)
		)
		(property "Value" ""
			(at 0 0 270)
			(layer "F.Fab")
			(effects
				(font
					(size 1.27 1.27)
				)
			)
		)
		(duplicate_pad_numbers_are_jumpers no)
		(fp_line
			(start -0.299974 0.150114)
			(end -0.299974 -0.150114)
			(stroke
				(width 0.1)
				(type default)
			)
			(layer "F.Fab")
		)
		(fp_line
			(start 0.299974 0.150114)
			(end -0.299974 0.150114)
			(stroke
				(width 0.1)
				(type default)
			)
			(layer "F.Fab")
		)
		(fp_line
			(start -0.299974 -0.150114)
			(end 0.299974 -0.150114)
			(stroke
				(width 0.1)
				(type default)
			)
			(layer "F.Fab")
		)
		(fp_line
			(start 0.299974 -0.150114)
			(end 0.299974 0.150114)
			(stroke
				(width 0.1)
				(type default)
			)
			(layer "F.Fab")
		)
		(pad "1" smd rect
			(at -0.2667 0 270)
			(size 0.3048 0.381)
			(layers "F.Cu" "F.Mask" "F.Paste")
			(net "P5E_CPU0_P0_TX_BUF_C_DP<5>")
		)
		(pad "2" smd rect
			(at 0.2667 0 270)
			(size 0.3048 0.381)
			(layers "F.Cu" "F.Mask" "F.Paste")
			(net "P5E_CPU0_P0_TX_BUF_DP<5>")
		)
	)
	(footprint ""
		(layer "F.Cu")
		(at 164.973 -96.012 90)
		(property "Reference" "C1058"
			(at 0 0 90)
			(layer "F.SilkS")
			(hide yes)
			(effects
				(font
					(size 1.27 1.27)
				)
			)
		)
		(property "Value" ""
			(at 0 0 90)
			(layer "F.Fab")
			(effects
				(font
					(size 1.27 1.27)
				)
			)
		)
		(duplicate_pad_numbers_are_jumpers no)
		(fp_line
			(start 0.7874 -0.4064)
			(end 0.7874 0.4064)
			(stroke
				(width 0.1524)
				(type default)
			)
			(layer "F.SilkS")
		)
		(fp_line
			(start -0.7874 -0.4064)
			(end 0.7874 -0.4064)
			(stroke
				(width 0.1524)
				(type default)
			)
			(layer "F.SilkS")
		)
		(fp_line
			(start 0.7874 0.4064)
			(end -0.7874 0.4064)
			(stroke
				(width 0.1524)
				(type default)
			)
			(layer "F.SilkS")
		)
		(fp_line
			(start -0.7874 0.4064)
			(end -0.7874 -0.4064)
			(stroke
				(width 0.1524)
				(type default)
			)
			(layer "F.SilkS")
		)
		(fp_line
			(start -0.12065 -0.305054)
			(end -0.12065 -0.2794)
			(stroke
				(width 0.1)
				(type default)
			)
			(layer "F.Fab")
		)
		(fp_line
			(start -0.67945 -0.305054)
			(end -0.12065 -0.305054)
			(stroke
				(width 0.1)
				(type default)
			)
			(layer "F.Fab")
		)
		(fp_line
			(start 0.67945 -0.3048)
			(end 0.67945 0.3048)
			(stroke
				(width 0.1)
				(type default)
			)
			(layer "F.Fab")
		)
		(fp_line
			(start 0.12065 -0.3048)
			(end 0.67945 -0.3048)
			(stroke
				(width 0.1)
				(type default)
			)
			(layer "F.Fab")
		)
		(fp_line
			(start 0.12065 -0.2794)
			(end 0.12065 -0.3048)
			(stroke
				(width 0.1)
				(type default)
			)
			(layer "F.Fab")
		)
		(fp_line
			(start -0.12065 -0.2794)
			(end 0.12065 -0.2794)
			(stroke
				(width 0.1)
				(type default)
			)
			(layer "F.Fab")
		)
		(fp_line
			(start 0.120396 0.2794)
			(end -0.12065 0.2794)
			(stroke
				(width 0.1)
				(type default)
			)
			(layer "F.Fab")
		)
		(fp_line
			(start -0.12065 0.2794)
			(end -0.12065 0.3048)
			(stroke
				(width 0.1)
				(type default)
			)
			(layer "F.Fab")
		)
		(fp_line
			(start 0.67945 0.3048)
			(end 0.120396 0.3048)
			(stroke
				(width 0.1)
				(type default)
			)
			(layer "F.Fab")
		)
		(fp_line
			(start 0.120396 0.3048)
			(end 0.120396 0.2794)
			(stroke
				(width 0.1)
				(type default)
			)
			(layer "F.Fab")
		)
		(fp_line
			(start -0.12065 0.3048)
			(end -0.67945 0.3048)
			(stroke
				(width 0.1)
				(type default)
			)
			(layer "F.Fab")
		)
		(fp_line
			(start -0.67945 0.3048)
			(end -0.67945 -0.305054)
			(stroke
				(width 0.1)
				(type default)
			)
			(layer "F.Fab")
		)
		(pad "1" smd circle
			(at -0.40005 0 90)
			(size 0 0)
			(layers "F.Cu" "F.Mask" "F.Paste")
			(net "P3V3_AUX")
		)
		(pad "2" smd circle
			(at 0.40005 0 90)
			(size 0 0)
			(layers "F.Cu" "F.Mask" "F.Paste")
			(net "GND")
		)
	)
	(footprint ""
		(layer "F.Cu")
		(at 111.633 -125.73 90)
		(property "Reference" "R6500"
			(at 0 0 90)
			(layer "F.SilkS")
			(hide yes)
			(effects
				(font
					(size 1.27 1.27)
				)
			)
		)
		(property "Value" ""
			(at 0 0 90)
			(layer "F.Fab")
			(effects
				(font
					(size 1.27 1.27)
				)
			)
		)
		(duplicate_pad_numbers_are_jumpers no)
		(fp_line
			(start 0.7874 -0.4064)
			(end 0.7874 0.4064)
			(stroke
				(width 0.1524)
				(type default)
			)
			(layer "F.SilkS")
		)
		(fp_line
			(start -0.7874 -0.4064)
			(end 0.7874 -0.4064)
			(stroke
				(width 0.1524)
				(type default)
			)
			(layer "F.SilkS")
		)
		(fp_line
			(start 0.7874 0.4064)
			(end -0.7874 0.4064)
			(stroke
				(width 0.1524)
				(type default)
			)
			(layer "F.SilkS")
		)
		(fp_line
			(start -0.7874 0.4064)
			(end -0.7874 -0.4064)
			(stroke
				(width 0.1524)
				(type default)
			)
			(layer "F.SilkS")
		)
		(fp_line
			(start -0.12065 -0.305054)
			(end -0.12065 -0.2794)
			(stroke
				(width 0.1)
				(type default)
			)
			(layer "F.Fab")
		)
		(fp_line
			(start -0.67945 -0.305054)
			(end -0.12065 -0.305054)
			(stroke
				(width 0.1)
				(type default)
			)
			(layer "F.Fab")
		)
		(fp_line
			(start 0.67945 -0.3048)
			(end 0.67945 0.3048)
			(stroke
				(width 0.1)
				(type default)
			)
			(layer "F.Fab")
		)
		(fp_line
			(start 0.12065 -0.3048)
			(end 0.67945 -0.3048)
			(stroke
				(width 0.1)
				(type default)
			)
			(layer "F.Fab")
		)
		(fp_line
			(start 0.12065 -0.2794)
			(end 0.12065 -0.3048)
			(stroke
				(width 0.1)
				(type default)
			)
			(layer "F.Fab")
		)
		(fp_line
			(start -0.12065 -0.2794)
			(end 0.12065 -0.2794)
			(stroke
				(width 0.1)
				(type default)
			)
			(layer "F.Fab")
		)
		(fp_line
			(start 0.120396 0.2794)
			(end -0.12065 0.2794)
			(stroke
				(width 0.1)
				(type default)
			)
			(layer "F.Fab")
		)
		(fp_line
			(start -0.12065 0.2794)
			(end -0.12065 0.3048)
			(stroke
				(width 0.1)
				(type default)
			)
			(layer "F.Fab")
		)
		(fp_line
			(start 0.67945 0.3048)
			(end 0.120396 0.3048)
			(stroke
				(width 0.1)
				(type default)
			)
			(layer "F.Fab")
		)
		(fp_line
			(start 0.120396 0.3048)
			(end 0.120396 0.2794)
			(stroke
				(width 0.1)
				(type default)
			)
			(layer "F.Fab")
		)
		(fp_line
			(start -0.12065 0.3048)
			(end -0.67945 0.3048)
			(stroke
				(width 0.1)
				(type default)
			)
			(layer "F.Fab")
		)
		(fp_line
			(start -0.67945 0.3048)
			(end -0.67945 -0.305054)
			(stroke
				(width 0.1)
				(type default)
			)
			(layer "F.Fab")
		)
		(pad "1" smd circle
			(at -0.40005 0 90)
			(size 0 0)
			(layers "F.Cu" "F.Mask" "F.Paste")
			(net "PWRGD_P3V3_EN_R")
		)
		(pad "2" smd circle
			(at 0.40005 0 90)
			(size 0 0)
			(layers "F.Cu" "F.Mask" "F.Paste")
			(net "PWRGD_P3V3_EN")
		)
	)
)
